# T6G (Grand Teton) — schematic netlist excerpt (pin names and nets, part order shuffled) for the footprints in the layout excerpt that follows; sources: Cadence DE-HDL packaged netlist, KiCad conversion of 04192023_DAF0TMB3IC0_F0TG_MB_C_brd_V02_OCP.brd

PR502  Q_RES  1.5 1% EMPTY  pkg 0402LF  page 198 : A = SW_PVDDCR_SOC_P0_SW1_RC ; B = GND
R588  Q_RES  33 5% CHIP  pkg 0402LF  page 81 : A = SCM_USB_OC_R_N ; B = SCM_USB_OC_N

(kicad_pcb
	(version 20260206)
	(generator "pcbnew")
	(generator_version "10.0")
	(general
		(thickness 1.6)
		(legacy_teardrops no)
	)
	(paper "A4")
	(title_block
		(title "04192023_DAF0TMB3IC0_F0TG_MB_C_brd_V02_OCP.brd")
		(comment 1 "Grand Teton / footprints 605-606 of 8354")
	)
	(layers
		(0 "F.Cu" signal "TOP")
		(4 "In1.Cu" signal "GND")
		(6 "In2.Cu" signal "IN1")
		(8 "In3.Cu" signal "GND1")
		(10 "In4.Cu" signal "IN2")
		(12 "In5.Cu" signal "GND2")
		(14 "In6.Cu" signal "IN3")
		(16 "In7.Cu" signal "GND3")
		(18 "In8.Cu" signal "VCC")
		(20 "In9.Cu" signal "VCC1")
		(22 "In10.Cu" signal "GND4")
		(24 "In11.Cu" signal "IN4")
		(26 "In12.Cu" signal "GND5")
		(28 "In13.Cu" signal "IN5")
		(30 "In14.Cu" signal "GND6")
		(32 "In15.Cu" signal "IN6")
		(34 "In16.Cu" signal "GND7")
		(2 "B.Cu" signal "BOTTOM")
		(9 "F.Adhes" user "F.Adhesive")
		(11 "B.Adhes" user "B.Adhesive")
		(13 "F.Paste" user "Package Geometry/Pastemask Top")
		(15 "B.Paste" user "Package Geometry/Pastemask Bottom")
		(5 "F.SilkS" user "Ref Des/Silkscreen Top")
		(7 "B.SilkS" user "Ref Des/Silkscreen Bottom")
		(1 "F.Mask" user "Board Geometry/Soldermask Top")
		(3 "B.Mask" user "Board Geometry/Soldermask Bottom")
		(17 "Dwgs.User" user "User.Drawings")
		(19 "Cmts.User" user "User.Comments")
		(21 "Eco1.User" user "User.Eco1")
		(23 "Eco2.User" user "User.Eco2")
		(25 "Edge.Cuts" user "Board Geometry/Outline")
		(27 "Margin" user)
		(31 "F.CrtYd" user "Package Geometry/Place Bound Top")
		(29 "B.CrtYd" user "Package Geometry/Place Bound Bottom")
		(35 "F.Fab" user "Ref Des/Assembly Top")
		(33 "B.Fab" user "Ref Des/Assembly Bottom")
	)
	(footprint ""
		(layer "F.Cu")
		(at 401.501356 -178.905408 -90)
		(property "Reference" "PR502"
			(at 0 0 270)
			(layer "F.SilkS")
			(hide yes)
			(effects
				(font
					(size 1.27 1.27)
				)
			)
		)
		(property "Value" ""
			(at 0 0 270)
			(layer "F.Fab")
			(effects
				(font
					(size 1.27 1.27)
				)
			)
		)
		(duplicate_pad_numbers_are_jumpers no)
		(fp_line
			(start -0.7874 0.4064)
			(end -0.7874 -0.4064)
			(stroke
				(width 0.1524)
				(type default)
			)
			(layer "F.SilkS")
		)
		(fp_line
			(start 0.7874 0.4064)
			(end -0.7874 0.4064)
			(stroke
				(width 0.1524)
				(type default)
			)
			(layer "F.SilkS")
		)
		(fp_line
			(start -0.7874 -0.4064)
			(end 0.7874 -0.4064)
			(stroke
				(width 0.1524)
				(type default)
			)
			(layer "F.SilkS")
		)
		(fp_line
			(start 0.7874 -0.4064)
			(end 0.7874 0.4064)
			(stroke
				(width 0.1524)
				(type default)
			)
			(layer "F.SilkS")
		)
		(fp_line
			(start -0.67945 0.3048)
			(end -0.67945 -0.305054)
			(stroke
				(width 0.1)
				(type default)
			)
			(layer "F.Fab")
		)
		(fp_line
			(start -0.12065 0.3048)
			(end -0.67945 0.3048)
			(stroke
				(width 0.1)
				(type default)
			)
			(layer "F.Fab")
		)
		(fp_line
			(start 0.120396 0.3048)
			(end 0.120396 0.2794)
			(stroke
				(width 0.1)
				(type default)
			)
			(layer "F.Fab")
		)
		(fp_line
			(start 0.67945 0.3048)
			(end 0.120396 0.3048)
			(stroke
				(width 0.1)
				(type default)
			)
			(layer "F.Fab")
		)
		(fp_line
			(start -0.12065 0.2794)
			(end -0.12065 0.3048)
			(stroke
				(width 0.1)
				(type default)
			)
			(layer "F.Fab")
		)
		(fp_line
			(start 0.120396 0.2794)
			(end -0.12065 0.2794)
			(stroke
				(width 0.1)
				(type default)
			)
			(layer "F.Fab")
		)
		(fp_line
			(start -0.12065 -0.2794)
			(end 0.12065 -0.2794)
			(stroke
				(width 0.1)
				(type default)
			)
			(layer "F.Fab")
		)
		(fp_line
			(start 0.12065 -0.2794)
			(end 0.12065 -0.3048)
			(stroke
				(width 0.1)
				(type default)
			)
			(layer "F.Fab")
		)
		(fp_line
			(start 0.12065 -0.3048)
			(end 0.67945 -0.3048)
			(stroke
				(width 0.1)
				(type default)
			)
			(layer "F.Fab")
		)
		(fp_line
			(start 0.67945 -0.3048)
			(end 0.67945 0.3048)
			(stroke
				(width 0.1)
				(type default)
			)
			(layer "F.Fab")
		)
		(fp_line
			(start -0.67945 -0.305054)
			(end -0.12065 -0.305054)
			(stroke
				(width 0.1)
				(type default)
			)
			(layer "F.Fab")
		)
		(fp_line
			(start -0.12065 -0.305054)
			(end -0.12065 -0.2794)
			(stroke
				(width 0.1)
				(type default)
			)
			(layer "F.Fab")
		)
		(pad "1" smd circle
			(at -0.40005 0 270)
			(size 0 0)
			(layers "F.Cu" "F.Mask" "F.Paste")
			(net "SW_PVDDCR_SOC_P0_SW1_RC")
		)
		(pad "2" smd circle
			(at 0.40005 0 270)
			(size 0 0)
			(layers "F.Cu" "F.Mask" "F.Paste")
			(net "GND")
		)
	)
	(footprint ""
		(layer "F.Cu")
		(at 191.135 -133.568948 90)
		(property "Reference" "R588"
			(at 0 0 90)
			(layer "F.SilkS")
			(hide yes)
			(effects
				(font
					(size 1.27 1.27)
				)
			)
		)
		(property "Value" ""
			(at 0 0 90)
			(layer "F.Fab")
			(effects
				(font
					(size 1.27 1.27)
				)
			)
		)
		(duplicate_pad_numbers_are_jumpers no)
		(fp_line
			(start 0.7874 -0.4064)
			(end 0.7874 0.4064)
			(stroke
				(width 0.1524)
				(type default)
			)
			(layer "F.SilkS")
		)
		(fp_line
			(start -0.7874 -0.4064)
			(end 0.7874 -0.4064)
			(stroke
				(width 0.1524)
				(type default)
			)
			(layer "F.SilkS")
		)
		(fp_line
			(start 0.7874 0.4064)
			(end -0.7874 0.4064)
			(stroke
				(width 0.1524)
				(type default)
			)
			(layer "F.SilkS")
		)
		(fp_line
			(start -0.7874 0.4064)
			(end -0.7874 -0.4064)
			(stroke
				(width 0.1524)
				(type default)
			)
			(layer "F.SilkS")
		)
		(fp_line
			(start -0.12065 -0.305054)
			(end -0.12065 -0.2794)
			(stroke
				(width 0.1)
				(type default)
			)
			(layer "F.Fab")
		)
		(fp_line
			(start -0.67945 -0.305054)
			(end -0.12065 -0.305054)
			(stroke
				(width 0.1)
				(type default)
			)
			(layer "F.Fab")
		)
		(fp_line
			(start 0.67945 -0.3048)
			(end 0.67945 0.3048)
			(stroke
				(width 0.1)
				(type default)
			)
			(layer "F.Fab")
		)
		(fp_line
			(start 0.12065 -0.3048)
			(end 0.67945 -0.3048)
			(stroke
				(width 0.1)
				(type default)
			)
			(layer "F.Fab")
		)
		(fp_line
			(start 0.12065 -0.2794)
			(end 0.12065 -0.3048)
			(stroke
				(width 0.1)
				(type default)
			)
			(layer "F.Fab")
		)
		(fp_line
			(start -0.12065 -0.2794)
			(end 0.12065 -0.2794)
			(stroke
				(width 0.1)
				(type default)
			)
			(layer "F.Fab")
		)
		(fp_line
			(start 0.120396 0.2794)
			(end -0.12065 0.2794)
			(stroke
				(width 0.1)
				(type default)
			)
			(layer "F.Fab")
		)
		(fp_line
			(start -0.12065 0.2794)
			(end -0.12065 0.3048)
			(stroke
				(width 0.1)
				(type default)
			)
			(layer "F.Fab")
		)
		(fp_line
			(start 0.67945 0.3048)
			(end 0.120396 0.3048)
			(stroke
				(width 0.1)
				(type default)
			)
			(layer "F.Fab")
		)
		(fp_line
			(start 0.120396 0.3048)
			(end 0.120396 0.2794)
			(stroke
				(width 0.1)
				(type default)
			)
			(layer "F.Fab")
		)
		(fp_line
			(start -0.12065 0.3048)
			(end -0.67945 0.3048)
			(stroke
				(width 0.1)
				(type default)
			)
			(layer "F.Fab")
		)
		(fp_line
			(start -0.67945 0.3048)
			(end -0.67945 -0.305054)
			(stroke
				(width 0.1)
				(type default)
			)
			(layer "F.Fab")
		)
		(pad "1" smd circle
			(at -0.40005 0 90)
			(size 0 0)
			(layers "F.Cu" "F.Mask" "F.Paste")
			(net "SCM_USB_OC_R_N")
		)
		(pad "2" smd circle
			(at 0.40005 0 90)
			(size 0 0)
			(layers "F.Cu" "F.Mask" "F.Paste")
			(net "SCM_USB_OC_N")
		)
	)
)
